# S9S_MB_2U (Grand Teton) — schematic netlist excerpt (pin names and nets, part order shuffled) for the footprints in the layout excerpt that follows; sources: Cadence DE-HDL packaged netlist, KiCad conversion of 03242023_DA0F0TMBIJ0_F0T_Motherboard_J_brd_V01_OCP.brd

J106  CONN112_10137002101LF  CONN112_10137002-101LF IO  pkg HSD_F112D8_P2W1-2_RDH  page 137
  A1  = PRSNT_CABLE_SWB_B1_N
  A2  = GND
  A3  = FM_SWB_PWRGD
  A4  = GND
  A5  = NC_J106_A5
  A6  = GND
  A7  = PRSNT_CABLE_GPU_A1_N
  A8  = GND
  B1  = GND
  B2  = P5E_CPU0_PE3_RX_DP<14>
  B3  = GND
  B4  = P5E_CPU0_PE3_RX_DP<12>
  B5  = GND
  B6  = P5E_CPU0_PE3_RX_DN<10>
  B7  = GND
  B8  = P5E_CPU0_PE3_RX_DN<8>
  C1  = P5E_CPU0_PE3_RX_DP<15>
  C2  = P5E_CPU0_PE3_RX_DN<14>
  C3  = P5E_CPU0_PE3_RX_DP<13>
  C4  = P5E_CPU0_PE3_RX_DN<12>
  C5  = P5E_CPU0_PE3_RX_DN<11>
  C6  = P5E_CPU0_PE3_RX_DP<10>
  C7  = P5E_CPU0_PE3_RX_DN<9>
  C8  = P5E_CPU0_PE3_RX_DP<8>
  D1  = P5E_CPU0_PE3_RX_DN<15>
  D2  = GND
  D3  = P5E_CPU0_PE3_RX_DN<13>
  D4  = GND
  D5  = P5E_CPU0_PE3_RX_DP<11>
  D6  = GND
  D7  = P5E_CPU0_PE3_RX_DP<9>
  D8  = GND
  E1  = GND
  E2  = P5E_CPU0_PE2_RX_DP<14>
  E3  = GND
  E4  = P5E_CPU0_PE2_RX_DP<12>
  E5  = GND
  E6  = P5E_CPU0_PE2_RX_DP<10>
  E7  = GND
  E8  = P5E_CPU0_PE2_RX_DP<8>
  F1  = P5E_CPU0_PE2_RX_DP<15>
  F2  = P5E_CPU0_PE2_RX_DN<14>
  F3  = P5E_CPU0_PE2_RX_DP<13>
  F4  = P5E_CPU0_PE2_RX_DN<12>
  F5  = P5E_CPU0_PE2_RX_DP<11>
  F6  = P5E_CPU0_PE2_RX_DN<10>
  F7  = P5E_CPU0_PE2_RX_DP<9>
  F8  = P5E_CPU0_PE2_RX_DN<8>
  G1  = P5E_CPU0_PE2_RX_DN<15>
  G2  = GND
  G3  = P5E_CPU0_PE2_RX_DN<13>
  G4  = GND
  G5  = P5E_CPU0_PE2_RX_DN<11>
  G6  = GND
  G7  = P5E_CPU0_PE2_RX_DN<9>
  G8  = GND
  H1  = GND
  H2  = P5E_CPU0_PE3_TX_C_DN<14>
  H3  = GND
  H4  = P5E_CPU0_PE3_TX_C_DN<12>
  H5  = GND
  H6  = P5E_CPU0_PE3_TX_C_DN<10>
  H7  = GND
  H8  = P5E_CPU0_PE3_TX_C_DN<8>
  I1  = P5E_CPU0_PE3_TX_C_DN<15>
  I2  = P5E_CPU0_PE3_TX_C_DP<14>
  I3  = P5E_CPU0_PE3_TX_C_DN<13>
  I4  = P5E_CPU0_PE3_TX_C_DP<12>
  I5  = P5E_CPU0_PE3_TX_C_DN<11>
  I6  = P5E_CPU0_PE3_TX_C_DP<10>
  I7  = P5E_CPU0_PE3_TX_C_DN<9>
  I8  = P5E_CPU0_PE3_TX_C_DP<8>
  J1  = P5E_CPU0_PE3_TX_C_DP<15>
  J2  = GND
  J3  = P5E_CPU0_PE3_TX_C_DP<13>
  J4  = GND
  J5  = P5E_CPU0_PE3_TX_C_DP<11>
  J6  = GND
  J7  = P5E_CPU0_PE3_TX_C_DP<9>
  J8  = GND
  K1  = GND
  K2  = P5E_CPU0_PE2_TX_C_DP<14>
  K3  = GND
  K4  = P5E_CPU0_PE2_TX_C_DP<12>
  K5  = GND
  K6  = P5E_CPU0_PE2_TX_C_DP<10>
  K7  = GND
  K8  = P5E_CPU0_PE2_TX_C_DP<8>
  L1  = P5E_CPU0_PE2_TX_C_DN<15>
  L2  = P5E_CPU0_PE2_TX_C_DN<14>
  L3  = P5E_CPU0_PE2_TX_C_DP<13>
  L4  = P5E_CPU0_PE2_TX_C_DN<12>
  L5  = P5E_CPU0_PE2_TX_C_DP<11>
  L6  = P5E_CPU0_PE2_TX_C_DN<10>
  L7  = P5E_CPU0_PE2_TX_C_DP<9>
  L8  = P5E_CPU0_PE2_TX_C_DN<8>
  M1  = P5E_CPU0_PE2_TX_C_DP<15>
  M2  = GND
  M3  = P5E_CPU0_PE2_TX_C_DN<13>
  M4  = GND
  M5  = P5E_CPU0_PE2_TX_C_DN<11>
  M6  = GND
  M7  = P5E_CPU0_PE2_TX_C_DN<9>
  M8  = GND
  N1  = GND
  N2  = I3C_BMC_SWB_BUF_SDA
  N3  = GND
  N4  = I3C_BMC_SWB_BUF_SCL
  N5  = GND
  N6  = UART_BMC_BIC_RX
  N7  = GND
  N8  = UART_BMC_BIC_TX

(kicad_pcb
	(version 20260206)
	(generator "pcbnew")
	(generator_version "10.0")
	(general
		(thickness 1.6)
		(legacy_teardrops no)
	)
	(paper "A4")
	(title_block
		(title "03242023_DA0F0TMBIJ0_F0T_Motherboard_J_brd_V01_OCP.brd")
		(comment 1 "Grand Teton / footprint 3156 of 6105 (J106), pads 32-48 of 48")
	)
	(layers
		(0 "F.Cu" signal "TOP")
		(4 "In1.Cu" signal "GND")
		(6 "In2.Cu" signal "IN1")
		(8 "In3.Cu" signal "GND1")
		(10 "In4.Cu" signal "IN2")
		(12 "In5.Cu" signal "GND2")
		(14 "In6.Cu" signal "IN3")
		(16 "In7.Cu" signal "GND3")
		(18 "In8.Cu" signal "VCC")
		(20 "In9.Cu" signal "VCC1")
		(22 "In10.Cu" signal "GND4")
		(24 "In11.Cu" signal "IN4")
		(26 "In12.Cu" signal "GND5")
		(28 "In13.Cu" signal "IN5")
		(30 "In14.Cu" signal "GND6")
		(32 "In15.Cu" signal "IN6")
		(34 "In16.Cu" signal "GND7")
		(2 "B.Cu" signal "BOTTOM")
		(9 "F.Adhes" user "F.Adhesive")
		(11 "B.Adhes" user "B.Adhesive")
		(13 "F.Paste" user "Package Geometry/Pastemask Top")
		(15 "B.Paste" user "Package Geometry/Pastemask Bottom")
		(5 "F.SilkS" user "Ref Des/Silkscreen Top")
		(7 "B.SilkS" user "Ref Des/Silkscreen Bottom")
		(1 "F.Mask" user "Board Geometry/Soldermask Top")
		(3 "B.Mask" user "Board Geometry/Soldermask Bottom")
		(17 "Dwgs.User" user "User.Drawings")
		(19 "Cmts.User" user "User.Comments")
		(21 "Eco1.User" user "User.Eco1")
		(23 "Eco2.User" user "User.Eco2")
		(25 "Edge.Cuts" user "Board Geometry/Outline")
		(27 "Margin" user)
		(31 "F.CrtYd" user "Package Geometry/Place Bound Top")
		(29 "B.CrtYd" user "Package Geometry/Place Bound Bottom")
		(35 "F.Fab" user "Ref Des/Assembly Top")
		(33 "B.Fab" user "Ref Des/Assembly Bottom")
	)
	(footprint ""
		(layer "F.Cu")
		(at 381.750062 -440.489848)
		(property "Reference" "J106"
			(at -7.488682 21.48459 0)
			(unlocked yes)
			(layer "F.SilkS")
			(effects
				(font
					(size 0.7874 0.5842)
					(thickness 0.1524)
				)
				(justify left)
			)
		)
		(property "Value" ""
			(at 0 0 0)
			(layer "F.Fab")
			(effects
				(font
					(size 1.27 1.27)
				)
			)
		)
		(duplicate_pad_numbers_are_jumpers no)
		(pad "J8" thru_hole circle
			(at 13.999972 10.999978 180)
			(size 0.906272 0.906272)
			(drill 0.499872)
			(layers "*.Cu" "*.Mask")
			(remove_unused_layers no)
			(net "GND")
			(clearance 0.0508)
			(thermal_gap 0.0508)
		)
		(pad "K1" thru_hole circle
			(at 0 11.999976 180)
			(size 0.906272 0.906272)
			(drill 0.499872)
			(layers "*.Cu" "*.Mask")
			(remove_unused_layers no)
			(net "GND")
			(clearance 0.0508)
			(thermal_gap 0.0508)
		)
		(pad "K3" thru_hole circle
			(at 3.999992 11.999976 180)
			(size 0.906272 0.906272)
			(drill 0.499872)
			(layers "*.Cu" "*.Mask")
			(remove_unused_layers no)
			(net "GND")
			(clearance 0.0508)
			(thermal_gap 0.0508)
		)
		(pad "K5" thru_hole circle
			(at 7.999984 11.999976 180)
			(size 0.906272 0.906272)
			(drill 0.499872)
			(layers "*.Cu" "*.Mask")
			(remove_unused_layers no)
			(net "GND")
			(clearance 0.0508)
			(thermal_gap 0.0508)
		)
		(pad "K7" thru_hole circle
			(at 11.999976 11.999976 180)
			(size 0.906272 0.906272)
			(drill 0.499872)
			(layers "*.Cu" "*.Mask")
			(remove_unused_layers no)
			(net "GND")
			(clearance 0.0508)
			(thermal_gap 0.0508)
		)
		(pad "M2" thru_hole circle
			(at 1.999996 14.59992 180)
			(size 0.906272 0.906272)
			(drill 0.499872)
			(layers "*.Cu" "*.Mask")
			(remove_unused_layers no)
			(net "GND")
			(clearance 0.0508)
			(thermal_gap 0.0508)
		)
		(pad "M4" thru_hole circle
			(at 5.999988 14.59992 180)
			(size 0.906272 0.906272)
			(drill 0.499872)
			(layers "*.Cu" "*.Mask")
			(remove_unused_layers no)
			(net "GND")
			(clearance 0.0508)
			(thermal_gap 0.0508)
		)
		(pad "M6" thru_hole circle
			(at 9.99998 14.59992 180)
			(size 0.906272 0.906272)
			(drill 0.499872)
			(layers "*.Cu" "*.Mask")
			(remove_unused_layers no)
			(net "GND")
			(clearance 0.0508)
			(thermal_gap 0.0508)
		)
		(pad "M8" thru_hole circle
			(at 13.999972 14.59992 180)
			(size 0.906272 0.906272)
			(drill 0.499872)
			(layers "*.Cu" "*.Mask")
			(remove_unused_layers no)
			(net "GND")
			(clearance 0.0508)
			(thermal_gap 0.0508)
		)
		(pad "N1" thru_hole circle
			(at 0 15.599918 180)
			(size 0.906272 0.906272)
			(drill 0.499872)
			(layers "*.Cu" "*.Mask")
			(remove_unused_layers no)
			(net "GND")
			(clearance 0.0508)
			(thermal_gap 0.0508)
		)
		(pad "N2" thru_hole circle
			(at 1.999996 15.80007 180)
			(size 0.766318 0.766318)
			(drill 0.359918)
			(layers "*.Cu" "*.Mask")
			(remove_unused_layers no)
			(net "I3C_BMC_SWB_BUF_SDA")
			(clearance 0.0508)
			(thermal_gap 0.0508)
		)
		(pad "N3" thru_hole circle
			(at 3.999992 15.599918 180)
			(size 0.906272 0.906272)
			(drill 0.499872)
			(layers "*.Cu" "*.Mask")
			(remove_unused_layers no)
			(net "GND")
			(clearance 0.0508)
			(thermal_gap 0.0508)
		)
		(pad "N4" thru_hole circle
			(at 5.999988 15.80007 180)
			(size 0.766318 0.766318)
			(drill 0.359918)
			(layers "*.Cu" "*.Mask")
			(remove_unused_layers no)
			(net "I3C_BMC_SWB_BUF_SCL")
			(clearance 0.0508)
			(thermal_gap 0.0508)
		)
		(pad "N5" thru_hole circle
			(at 7.999984 15.599918 180)
			(size 0.906272 0.906272)
			(drill 0.499872)
			(layers "*.Cu" "*.Mask")
			(remove_unused_layers no)
			(net "GND")
			(clearance 0.0508)
			(thermal_gap 0.0508)
		)
		(pad "N6" thru_hole circle
			(at 9.99998 15.80007 180)
			(size 0.766318 0.766318)
			(drill 0.359918)
			(layers "*.Cu" "*.Mask")
			(remove_unused_layers no)
			(net "UART_BMC_BIC_RX")
			(clearance 0.0508)
			(thermal_gap 0.0508)
		)
		(pad "N7" thru_hole circle
			(at 11.999976 15.599918 180)
			(size 0.906272 0.906272)
			(drill 0.499872)
			(layers "*.Cu" "*.Mask")
			(remove_unused_layers no)
			(net "GND")
			(clearance 0.0508)
			(thermal_gap 0.0508)
		)
		(pad "N8" thru_hole circle
			(at 13.999972 15.80007 180)
			(size 0.766318 0.766318)
			(drill 0.359918)
			(layers "*.Cu" "*.Mask")
			(remove_unused_layers no)
			(net "UART_BMC_BIC_TX")
			(clearance 0.0508)
			(thermal_gap 0.0508)
		)
	)
)
